# S9S_MB_2U (Grand Teton) — schematic netlist excerpt (pin names and nets, part order shuffled) for the footprints in the layout excerpt that follows; sources: Cadence DE-HDL packaged netlist, KiCad conversion of 03242023_DA0F0TMBIJ0_F0T_Motherboard_J_brd_V01_OCP.brd

J3  SCONN288_ADR50017P130CC  SCONN288_ADR50017-P130CC IO  pkg DDR288S_1-1VXB  page 84
  VIN_BULK0  = P12V_S3_AUX_CPU0_NVDIMM
  RFU0  = TP_CHB_CPU0_DIMM1_FRU_0
  VIN_MGMT  = P3V3_AUX
  HSCL  = I3C_SPD_DDRABCD_CPU0_LVC1_SCL_2
  HSDA  = I3C_SPD_DDRABCD_CPU0_LVC1_SDA
  VSS0  = GND
  DQ0_A  = M_B_CPU0_SA_DQ<0>
  VSS1  = GND
  DQ1_A  = M_B_CPU0_SA_DQ<1>
  VSS2  = GND
  DQS0_A_T  = M_B_CPU0_SA_DQS_DP<0>
  DQS0_A_C  = M_B_CPU0_SA_DQS_DN<0>
  VSS3  = GND
  DQ4_A  = M_B_CPU0_SA_DQ<4>
  VSS4  = GND
  DQ5_A  = M_B_CPU0_SA_DQ<5>
  VSS5  = GND
  DQ8_A  = M_B_CPU0_SA_DQ<8>
  VSS6  = GND
  DQ9_A  = M_B_CPU0_SA_DQ<9>
  VSS7  = GND
  DQS1_A_T  = M_B_CPU0_SA_DQS_DP<1>
  DQS1_A_C  = M_B_CPU0_SA_DQS_DN<1>
  VSS8  = GND
  DQ12_A  = M_B_CPU0_SA_DQ<12>
  VSS9  = GND
  DQ13_A  = M_B_CPU0_SA_DQ<13>
  VSS10  = GND
  DQ16_A  = M_B_CPU0_SA_DQ<16>
  VSS11  = GND
  DQ17_A  = M_B_CPU0_SA_DQ<17>
  VSS12  = GND
  DQS2_A_T  = M_B_CPU0_SA_DQS_DP<2>
  DQS2_A_C  = M_B_CPU0_SA_DQS_DN<2>
  VSS13  = GND
  DQ20_A  = M_B_CPU0_SA_DQ<20>
  VSS14  = GND
  DQ21_A  = M_B_CPU0_SA_DQ<21>
  VSS15  = GND
  DQ24_A  = M_B_CPU0_SA_DQ<24>
  VSS16  = GND
  DQ25_A  = M_B_CPU0_SA_DQ<25>
  VSS17  = GND
  DQS3_A_T  = M_B_CPU0_SA_DQS_DP<3>
  DQS3_A_C  = M_B_CPU0_SA_DQS_DN<3>
  VSS18  = GND
  DQ28_A  = M_B_CPU0_SA_DQ<28>
  VSS19  = GND
  DQ29_A  = M_B_CPU0_SA_DQ<29>
  VSS20  = GND
  CB0_A  = M_B_CPU0_SA_CB<0>
  VSS21  = GND
  CB1_A  = M_B_CPU0_SA_CB<1>
  VSS22  = GND
  DQS4_A_T  = M_B_CPU0_SA_DQS_DP<4>
  DQS4_A_C  = M_B_CPU0_SA_DQS_DN<4>
  VSS23  = GND
  CB4_A  = M_B_CPU0_SA_CB<4>
  VSS24  = GND
  CB5_A  = M_B_CPU0_SA_CB<5>
  VSS25  = GND
  ALERT_N  = M_B_CPU0_ALERT_N
  VSS26  = GND
  CS0_A_N  = M_B_CPU0_SA_CS_N<0>
  VSS27  = GND
  CA0_A  = M_B_CPU0_SA_CA<0>
  VSS28  = GND
  CA2_A  = M_B_CPU0_SA_CA<2>
  VSS29  = GND
  CA4_A  = M_B_CPU0_SA_CA<4>
  VSS30  = GND
  CA6_A  = M_B_CPU0_SA_CA<6>
  VSS31  = GND
  PAR_A  = M_B_CPU0_SA_PAR
  VSS32  = GND
  CA0_B  = M_B_CPU0_SB_CA<0>
  VSS33  = GND
  CA2_B  = M_B_CPU0_SB_CA<2>
  VSS34  = GND
  CA4_B  = M_B_CPU0_SB_CA<4>
  VSS35  = GND
  CA6_B  = M_B_CPU0_SB_CA<6>
  VSS36  = GND
  CS0_B_N  = M_B_CPU0_SB_CS_N<0>
  VSS37  = GND
  \lbd||rsp_a_n\  = M_B_CPU0_SA_RSP<0>
  \lbs||rsp_b_n\  = M_B_CPU0_SB_RSP<0>
  VSS38  = GND
  CB4_B  = M_B_CPU0_SB_CB<4>
  VSS39  = GND
  CB5_B  = M_B_CPU0_SB_CB<5>
  VSS40  = GND
  \dqs9_b_t||tdqs9_b_t||dbi4_b_n\  = M_B_CPU0_SB_DQS_DP<9>
  \dqs9_b_c||tdqs9_b_c\  = M_B_CPU0_SB_DQS_DN<9>
  VSS41  = GND
  CB0_B  = M_B_CPU0_SB_CB<0>
  VSS42  = GND
  CB1_B  = M_B_CPU0_SB_CB<1>
  VSS43  = GND
  DQ0_B  = M_B_CPU0_SB_DQ<0>
  VSS44  = GND
  DQ1_B  = M_B_CPU0_SB_DQ<1>
  VSS45  = GND
  DQS0_B_T  = M_B_CPU0_SB_DQS_DP<0>
  DQS0_B_C  = M_B_CPU0_SB_DQS_DN<0>
  VSS46  = GND
  DQ4_B  = M_B_CPU0_SB_DQ<4>
  VSS47  = GND
  DQ5_B  = M_B_CPU0_SB_DQ<5>
  VSS48  = GND
  DQ8_B  = M_B_CPU0_SB_DQ<8>
  VSS49  = GND
  DQ9_B  = M_B_CPU0_SB_DQ<9>
  VSS50  = GND
  DQS1_B_T  = M_B_CPU0_SB_DQS_DP<1>
  DQS1_B_C  = M_B_CPU0_SB_DQS_DN<1>
  VSS51  = GND
  DQ12_B  = M_B_CPU0_SB_DQ<12>
  VSS52  = GND
  DQ13_B  = M_B_CPU0_SB_DQ<13>
  VSS53  = GND
  DQ16_B  = M_B_CPU0_SB_DQ<16>
  VSS54  = GND
  DQ17_B  = M_B_CPU0_SB_DQ<17>
  VSS55  = GND
  DQS2_B_T  = M_B_CPU0_SB_DQS_DP<2>
  DQS2_B_C  = M_B_CPU0_SB_DQS_DN<2>
  VSS56  = GND
  DQ20_B  = M_B_CPU0_SB_DQ<20>
  VSS57  = GND
  DQ21_B  = M_B_CPU0_SB_DQ<21>
  VSS58  = GND
  DQ24_B  = M_B_CPU0_SB_DQ<24>
  VSS59  = GND
  DQ25_B  = M_B_CPU0_SB_DQ<25>
  VSS60  = GND
  DQS3_B_T  = M_B_CPU0_SB_DQS_DP<3>
  DQS3_B_C  = M_B_CPU0_SB_DQS_DN<3>
  VSS61  = GND
  DQ28_B  = M_B_CPU0_SB_DQ<28>
  VSS62  = GND
  DQ29_B  = M_B_CPU0_SB_DQ<29>
  VSS63  = GND
  RFU1  = TP_CHB_CPU0_DIMM1_FRU_1
  VIN_BULK1  = P12V_S3_AUX_CPU0_NVDIMM
  VIN_BULK2  = P12V_S3_AUX_CPU0_NVDIMM
  \pwr_good||fail_n\  = PWRGD_CHB_CPU0_DIMM1
  HSA  = PD_CHB_CPU0_DIMM1_SAA
  RFU2  = TP_CHB_CPU0_DIMM1_FRU_2
  RFU3  = TP_CHB_CPU0_DIMM1_FRU_3
  VSS64  = GND
  DQ2_A  = M_B_CPU0_SA_DQ<2>
  VSS65  = GND
  DQ3_A  = M_B_CPU0_SA_DQ<3>
  VSS66  = GND
  \dqs5_a_c||tdqs5_a_c||dqs5_a_t||tdqs5_a_t\  = M_B_CPU0_SA_DQS_DN<5>
  \dqs5_a_t||tdqs5_a_t\  = M_B_CPU0_SA_DQS_DP<5>
  VSS67  = GND
  DQ6_A  = M_B_CPU0_SA_DQ<6>
  VSS68  = GND
  DQ7_A  = M_B_CPU0_SA_DQ<7>
  VSS69  = GND
  DQ10_A  = M_B_CPU0_SA_DQ<10>
  VSS70  = GND
  DQ11_A  = M_B_CPU0_SA_DQ<11>
  VSS71  = GND
  \dqs6_a_c||tdqs6_a_c||dqs6_a_t||tdqs6_a_t\  = M_B_CPU0_SA_DQS_DN<6>
  \dqs6_a_t||tdqs6_a_t\  = M_B_CPU0_SA_DQS_DP<6>
  VSS72  = GND
  DQ14_A  = M_B_CPU0_SA_DQ<14>
  VSS73  = GND
  DQ15_A  = M_B_CPU0_SA_DQ<15>
  VSS74  = GND
  DQ18_A  = M_B_CPU0_SA_DQ<18>
  VSS75  = GND
  DQ19_A  = M_B_CPU0_SA_DQ<19>
  VSS76  = GND
  \dqs7_a_c||tdqs7_a_c\  = M_B_CPU0_SA_DQS_DN<7>
  \dqs7_a_t||tdqs7_a_t\  = M_B_CPU0_SA_DQS_DP<7>
  VSS77  = GND
  DQ22_A  = M_B_CPU0_SA_DQ<22>
  VSS78  = GND
  DQ23_A  = M_B_CPU0_SA_DQ<23>
  VSS79  = GND
  DQ26_A  = M_B_CPU0_SA_DQ<26>
  VSS80  = GND
  DQ27_A  = M_B_CPU0_SA_DQ<27>
  VSS81  = GND
  \dqs8_a_c||tdqs8_a_c\  = M_B_CPU0_SA_DQS_DN<8>
  \dqs8_a_t||tdqs8_a_t\  = M_B_CPU0_SA_DQS_DP<8>
  VSS82  = GND
  DQ30_A  = M_B_CPU0_SA_DQ<30>
  VSS83  = GND
  DQ31_A  = M_B_CPU0_SA_DQ<31>
  VSS84  = GND
  CB2_A  = M_B_CPU0_SA_CB<2>
  VSS85  = GND
  CB3_A  = M_B_CPU0_SA_CB<3>
  VSS86  = GND
  \dqs9_a_c||tdqs9_a_c\  = M_B_CPU0_SA_DQS_DN<9>
  \dqs9_a_t||tdqs9_a_t\  = M_B_CPU0_SA_DQS_DP<9>
  VSS87  = GND
  CB6_A  = M_B_CPU0_SA_CB<6>
  VSS88  = GND
  CB7_A  = M_B_CPU0_SA_CB<7>
  VSS89  = GND
  RESET_N  = RST_M_AB_CPU0_FPGA_N
  VSS90  = GND
  CS1_A_N  = M_B_CPU0_SA_CS_N<1>
  VSS91  = GND
  CA1_A  = M_B_CPU0_SA_CA<1>
  VSS92  = GND
  CA3_A  = M_B_CPU0_SA_CA<3>
  VSS93  = GND
  CA5_A  = M_B_CPU0_SA_CA<5>
  VSS94  = GND
  CK_T  = M_B_CPU0_CLK_DP<0>
  CK_C  = M_B_CPU0_CLK_DN<0>
  VSS95  = GND
  RFU4  = TP_CHB_CPU0_DIMM1_FRU_4
  CA1_B  = M_B_CPU0_SB_CA<1>
  VSS96  = GND
  CA3_B  = M_B_CPU0_SB_CA<3>
  VSS97  = GND
  CA5_B  = M_B_CPU0_SB_CA<5>
  VSS98  = GND
  PAR_B  = M_B_CPU0_SB_PAR
  VSS99  = GND
  CS1_B_N  = M_B_CPU0_SB_CS_N<1>
  VSS100  = GND
  RFU5  = TP_CHB_CPU0_DIMM1_FRU_5
  RFU6  = TP_CHB_CPU0_DIMM1_FRU_6
  VSS101  = GND
  CB6_B  = M_B_CPU0_SB_CB<6>
  VSS102  = GND
  CB7_B  = M_B_CPU0_SB_CB<7>
  VSS103  = GND
  DQS4_B_C  = M_B_CPU0_SB_DQS_DN<4>
  DQS4_B_T  = M_B_CPU0_SB_DQS_DP<4>
  VSS104  = GND
  CB2_B  = M_B_CPU0_SB_CB<2>
  VSS105  = GND
  CB3_B  = M_B_CPU0_SB_CB<3>
  VSS106  = GND
  DQ2_B  = M_B_CPU0_SB_DQ<2>
  VSS107  = GND
  DQ3_B  = M_B_CPU0_SB_DQ<3>
  VSS108  = GND
  \dqs5_b_c||tdqs5_b_c\  = M_B_CPU0_SB_DQS_DN<5>
  \dqs5_b_t||tdqs5_b_t\  = M_B_CPU0_SB_DQS_DP<5>
  VSS109  = GND
  DQ6_B  = M_B_CPU0_SB_DQ<6>
  VSS110  = GND
  DQ7_B  = M_B_CPU0_SB_DQ<7>
  VSS111  = GND
  DQ10_B  = M_B_CPU0_SB_DQ<10>
  VSS112  = GND
  DQ11_B  = M_B_CPU0_SB_DQ<11>
  VSS113  = GND
  \dqs6_b_c||tdqs6_b_c\  = M_B_CPU0_SB_DQS_DN<6>
  \dqs6_b_t||tdqs6_b_t\  = M_B_CPU0_SB_DQS_DP<6>
  VSS114  = GND
  DQ14_B  = M_B_CPU0_SB_DQ<14>
  VSS115  = GND
  DQ15_B  = M_B_CPU0_SB_DQ<15>
  VSS116  = GND
  DQ18_B  = M_B_CPU0_SB_DQ<18>
  VSS117  = GND
  DQ19_B  = M_B_CPU0_SB_DQ<19>
  VSS118  = GND
  \dqs7_b_c||tdqs7_b_c\  = M_B_CPU0_SB_DQS_DN<7>
  \dqs7_b_t||tdqs7_b_t\  = M_B_CPU0_SB_DQS_DP<7>
  VSS119  = GND
  DQ22_B  = M_B_CPU0_SB_DQ<22>
  VSS120  = GND
  DQ23_B  = M_B_CPU0_SB_DQ<23>
  VSS121  = GND
  DQ26_B  = M_B_CPU0_SB_DQ<26>
  VSS122  = GND
  DQ27_B  = M_B_CPU0_SB_DQ<27>
  VSS123  = GND
  \dqs8_b_c||tdqs8_b_c\  = M_B_CPU0_SB_DQS_DN<8>
  \dqs8_b_t||tdqs8_b_t\  = M_B_CPU0_SB_DQS_DP<8>
  VSS124  = GND
  DQ30_B  = M_B_CPU0_SB_DQ<30>
  VSS125  = GND
  DQ31_B  = M_B_CPU0_SB_DQ<31>
  VSS126  = GND
  G1  = GND
  G2  = GND
  G3  = GND

(kicad_pcb
	(version 20260206)
	(generator "pcbnew")
	(generator_version "10.0")
	(general
		(thickness 1.6)
		(legacy_teardrops no)
	)
	(paper "A4")
	(title_block
		(title "03242023_DA0F0TMBIJ0_F0T_Motherboard_J_brd_V01_OCP.brd")
		(comment 1 "Grand Teton / footprint 2048 of 6105 (J3), pads 275-291 of 291")
	)
	(layers
		(0 "F.Cu" signal "TOP")
		(4 "In1.Cu" signal "GND")
		(6 "In2.Cu" signal "IN1")
		(8 "In3.Cu" signal "GND1")
		(10 "In4.Cu" signal "IN2")
		(12 "In5.Cu" signal "GND2")
		(14 "In6.Cu" signal "IN3")
		(16 "In7.Cu" signal "GND3")
		(18 "In8.Cu" signal "VCC")
		(20 "In9.Cu" signal "VCC1")
		(22 "In10.Cu" signal "GND4")
		(24 "In11.Cu" signal "IN4")
		(26 "In12.Cu" signal "GND5")
		(28 "In13.Cu" signal "IN5")
		(30 "In14.Cu" signal "GND6")
		(32 "In15.Cu" signal "IN6")
		(34 "In16.Cu" signal "GND7")
		(2 "B.Cu" signal "BOTTOM")
		(9 "F.Adhes" user "F.Adhesive")
		(11 "B.Adhes" user "B.Adhesive")
		(13 "F.Paste" user "Package Geometry/Pastemask Top")
		(15 "B.Paste" user "Package Geometry/Pastemask Bottom")
		(5 "F.SilkS" user "Ref Des/Silkscreen Top")
		(7 "B.SilkS" user "Ref Des/Silkscreen Bottom")
		(1 "F.Mask" user "Board Geometry/Soldermask Top")
		(3 "B.Mask" user "Board Geometry/Soldermask Bottom")
		(17 "Dwgs.User" user "User.Drawings")
		(19 "Cmts.User" user "User.Comments")
		(21 "Eco1.User" user "User.Eco1")
		(23 "Eco2.User" user "User.Eco2")
		(25 "Edge.Cuts" user "Board Geometry/Outline")
		(27 "Margin" user)
		(31 "F.CrtYd" user "Package Geometry/Place Bound Top")
		(29 "B.CrtYd" user "Package Geometry/Place Bound Bottom")
		(35 "F.Fab" user "Ref Des/Assembly Top")
		(33 "B.Fab" user "Ref Des/Assembly Bottom")
	)
	(footprint ""
		(layer "F.Cu")
		(at 288.305748 -258.091686)
		(property "Reference" "J3"
			(at -3.683 -81.702148 0)
			(unlocked yes)
			(layer "F.SilkS")
			(effects
				(font
					(size 0.7874 0.5842)
					(thickness 0.1524)
				)
				(justify left)
			)
		)
		(property "Value" ""
			(at 0 0 0)
			(layer "F.Fab")
			(effects
				(font
					(size 1.27 1.27)
				)
			)
		)
		(duplicate_pad_numbers_are_jumpers no)
		(pad "275" smd rect
			(at 2.050034 52.274978 270)
			(size 0.519938 1.4986)
			(layers "F.Cu" "F.Mask" "F.Paste")
			(net "GND")
		)
		(pad "276" smd rect
			(at 2.050034 53.125116 270)
			(size 0.519938 1.4986)
			(layers "F.Cu" "F.Mask" "F.Paste")
			(net "M_B_CPU0_SB_DQ<23>")
		)
		(pad "277" smd rect
			(at 2.050034 53.975 270)
			(size 0.519938 1.4986)
			(layers "F.Cu" "F.Mask" "F.Paste")
			(net "GND")
		)
		(pad "278" smd rect
			(at 2.050034 54.824884 270)
			(size 0.519938 1.4986)
			(layers "F.Cu" "F.Mask" "F.Paste")
			(net "M_B_CPU0_SB_DQ<26>")
		)
		(pad "279" smd rect
			(at 2.050034 55.675022 270)
			(size 0.519938 1.4986)
			(layers "F.Cu" "F.Mask" "F.Paste")
			(net "GND")
		)
		(pad "280" smd rect
			(at 2.050034 56.524906 270)
			(size 0.519938 1.4986)
			(layers "F.Cu" "F.Mask" "F.Paste")
			(net "M_B_CPU0_SB_DQ<27>")
		)
		(pad "281" smd rect
			(at 2.050034 57.375044 270)
			(size 0.519938 1.4986)
			(layers "F.Cu" "F.Mask" "F.Paste")
			(net "GND")
		)
		(pad "282" smd rect
			(at 2.050034 58.224928 270)
			(size 0.519938 1.4986)
			(layers "F.Cu" "F.Mask" "F.Paste")
			(net "M_B_CPU0_SB_DQS_DN<8>")
		)
		(pad "283" smd rect
			(at 2.050034 59.075066 270)
			(size 0.519938 1.4986)
			(layers "F.Cu" "F.Mask" "F.Paste")
			(net "M_B_CPU0_SB_DQS_DP<8>")
		)
		(pad "284" smd rect
			(at 2.050034 59.92495 270)
			(size 0.519938 1.4986)
			(layers "F.Cu" "F.Mask" "F.Paste")
			(net "GND")
		)
		(pad "285" smd rect
			(at 2.050034 60.775088 270)
			(size 0.519938 1.4986)
			(layers "F.Cu" "F.Mask" "F.Paste")
			(net "M_B_CPU0_SB_DQ<30>")
		)
		(pad "286" smd rect
			(at 2.050034 61.624972 270)
			(size 0.519938 1.4986)
			(layers "F.Cu" "F.Mask" "F.Paste")
			(net "GND")
		)
		(pad "287" smd rect
			(at 2.050034 62.47511 270)
			(size 0.519938 1.4986)
			(layers "F.Cu" "F.Mask" "F.Paste")
			(net "M_B_CPU0_SB_DQ<31>")
		)
		(pad "288" smd rect
			(at 2.050034 63.324994 270)
			(size 0.519938 1.4986)
			(layers "F.Cu" "F.Mask" "F.Paste")
			(net "GND")
		)
		(pad "G1" thru_hole oval
			(at 0 -68.97497)
			(size 2.8194 1.5748)
			(drill oval 2.4384 1.1938)
			(layers "*.Cu" "*.Mask")
			(remove_unused_layers no)
			(net "GND")
			(clearance 0.127)
			(thermal_gap 0.127)
		)
		(pad "G2" thru_hole oval
			(at 0 3.875024)
			(size 2.8194 1.5748)
			(drill oval 2.4384 1.1938)
			(layers "*.Cu" "*.Mask")
			(remove_unused_layers no)
			(net "GND")
			(clearance 0.127)
			(thermal_gap 0.127)
		)
		(pad "G3" thru_hole oval
			(at 0 68.97497)
			(size 2.8194 1.5748)
			(drill oval 2.4384 1.1938)
			(layers "*.Cu" "*.Mask")
			(remove_unused_layers no)
			(net "GND")
			(clearance 0.127)
			(thermal_gap 0.127)
		)
	)
)
